# T6G (Grand Teton) — schematic netlist excerpt (pin names and nets, part order shuffled) for the footprints in the layout excerpt that follows; sources: Cadence DE-HDL packaged netlist, KiCad conversion of 04192023_DAF0TMB3IC0_F0TG_MB_C_brd_V02_OCP.brd

R357  Q_RES  0 5% CHIP  pkg 0402LF  page 27 : A = CPU0_XTRIG_R2_L7 ; B = CPU0_XTRIG_L7
PR448  Q_RES  8.66K 1% CHIP  pkg 0402LF  page 209 : A = PVDD18_S5_P0_CS ; B = GND

(kicad_pcb
	(version 20260206)
	(generator "pcbnew")
	(generator_version "10.0")
	(general
		(thickness 1.6)
		(legacy_teardrops no)
	)
	(paper "A4")
	(title_block
		(title "04192023_DAF0TMB3IC0_F0TG_MB_C_brd_V02_OCP.brd")
		(comment 1 "Grand Teton / footprints 2202-2203 of 8354")
	)
	(layers
		(0 "F.Cu" signal "TOP")
		(4 "In1.Cu" signal "GND")
		(6 "In2.Cu" signal "IN1")
		(8 "In3.Cu" signal "GND1")
		(10 "In4.Cu" signal "IN2")
		(12 "In5.Cu" signal "GND2")
		(14 "In6.Cu" signal "IN3")
		(16 "In7.Cu" signal "GND3")
		(18 "In8.Cu" signal "VCC")
		(20 "In9.Cu" signal "VCC1")
		(22 "In10.Cu" signal "GND4")
		(24 "In11.Cu" signal "IN4")
		(26 "In12.Cu" signal "GND5")
		(28 "In13.Cu" signal "IN5")
		(30 "In14.Cu" signal "GND6")
		(32 "In15.Cu" signal "IN6")
		(34 "In16.Cu" signal "GND7")
		(2 "B.Cu" signal "BOTTOM")
		(9 "F.Adhes" user "F.Adhesive")
		(11 "B.Adhes" user "B.Adhesive")
		(13 "F.Paste" user "Package Geometry/Pastemask Top")
		(15 "B.Paste" user "Package Geometry/Pastemask Bottom")
		(5 "F.SilkS" user "Ref Des/Silkscreen Top")
		(7 "B.SilkS" user "Ref Des/Silkscreen Bottom")
		(1 "F.Mask" user "Board Geometry/Soldermask Top")
		(3 "B.Mask" user "Board Geometry/Soldermask Bottom")
		(17 "Dwgs.User" user "User.Drawings")
		(19 "Cmts.User" user "User.Comments")
		(21 "Eco1.User" user "User.Eco1")
		(23 "Eco2.User" user "User.Eco2")
		(25 "Edge.Cuts" user "Board Geometry/Outline")
		(27 "Margin" user)
		(31 "F.CrtYd" user "Package Geometry/Place Bound Top")
		(29 "B.CrtYd" user "Package Geometry/Place Bound Bottom")
		(35 "F.Fab" user "Ref Des/Assembly Top")
		(33 "B.Fab" user "Ref Des/Assembly Bottom")
	)
	(footprint ""
		(layer "F.Cu")
		(at 331.653642 -142.293086 180)
		(property "Reference" "PR448"
			(at 0 0 180)
			(layer "F.SilkS")
			(hide yes)
			(effects
				(font
					(size 1.27 1.27)
				)
			)
		)
		(property "Value" ""
			(at 0 0 180)
			(layer "F.Fab")
			(effects
				(font
					(size 1.27 1.27)
				)
			)
		)
		(duplicate_pad_numbers_are_jumpers no)
		(fp_line
			(start 0.7874 0.4064)
			(end -0.7874 0.4064)
			(stroke
				(width 0.1524)
				(type default)
			)
			(layer "F.SilkS")
		)
		(fp_line
			(start 0.7874 -0.4064)
			(end 0.7874 0.4064)
			(stroke
				(width 0.1524)
				(type default)
			)
			(layer "F.SilkS")
		)
		(fp_line
			(start -0.7874 0.4064)
			(end -0.7874 -0.4064)
			(stroke
				(width 0.1524)
				(type default)
			)
			(layer "F.SilkS")
		)
		(fp_line
			(start -0.7874 -0.4064)
			(end 0.7874 -0.4064)
			(stroke
				(width 0.1524)
				(type default)
			)
			(layer "F.SilkS")
		)
		(fp_line
			(start 0.67945 0.3048)
			(end 0.120396 0.3048)
			(stroke
				(width 0.1)
				(type default)
			)
			(layer "F.Fab")
		)
		(fp_line
			(start 0.67945 -0.3048)
			(end 0.67945 0.3048)
			(stroke
				(width 0.1)
				(type default)
			)
			(layer "F.Fab")
		)
		(fp_line
			(start 0.12065 -0.2794)
			(end 0.12065 -0.3048)
			(stroke
				(width 0.1)
				(type default)
			)
			(layer "F.Fab")
		)
		(fp_line
			(start 0.12065 -0.3048)
			(end 0.67945 -0.3048)
			(stroke
				(width 0.1)
				(type default)
			)
			(layer "F.Fab")
		)
		(fp_line
			(start 0.120396 0.3048)
			(end 0.120396 0.2794)
			(stroke
				(width 0.1)
				(type default)
			)
			(layer "F.Fab")
		)
		(fp_line
			(start 0.120396 0.2794)
			(end -0.12065 0.2794)
			(stroke
				(width 0.1)
				(type default)
			)
			(layer "F.Fab")
		)
		(fp_line
			(start -0.12065 0.3048)
			(end -0.67945 0.3048)
			(stroke
				(width 0.1)
				(type default)
			)
			(layer "F.Fab")
		)
		(fp_line
			(start -0.12065 0.2794)
			(end -0.12065 0.3048)
			(stroke
				(width 0.1)
				(type default)
			)
			(layer "F.Fab")
		)
		(fp_line
			(start -0.12065 -0.2794)
			(end 0.12065 -0.2794)
			(stroke
				(width 0.1)
				(type default)
			)
			(layer "F.Fab")
		)
		(fp_line
			(start -0.12065 -0.305054)
			(end -0.12065 -0.2794)
			(stroke
				(width 0.1)
				(type default)
			)
			(layer "F.Fab")
		)
		(fp_line
			(start -0.67945 0.3048)
			(end -0.67945 -0.305054)
			(stroke
				(width 0.1)
				(type default)
			)
			(layer "F.Fab")
		)
		(fp_line
			(start -0.67945 -0.305054)
			(end -0.12065 -0.305054)
			(stroke
				(width 0.1)
				(type default)
			)
			(layer "F.Fab")
		)
		(pad "1" smd circle
			(at -0.40005 0 180)
			(size 0 0)
			(layers "F.Cu" "F.Mask" "F.Paste")
			(net "PVDD18_S5_P0_CS")
		)
		(pad "2" smd circle
			(at 0.40005 0 180)
			(size 0 0)
			(layers "F.Cu" "F.Mask" "F.Paste")
			(net "GND")
		)
	)
	(footprint ""
		(layer "F.Cu")
		(at 329.355958 -194.052952 -90)
		(property "Reference" "R357"
			(at 0 0 270)
			(layer "F.SilkS")
			(hide yes)
			(effects
				(font
					(size 1.27 1.27)
				)
			)
		)
		(property "Value" ""
			(at 0 0 270)
			(layer "F.Fab")
			(effects
				(font
					(size 1.27 1.27)
				)
			)
		)
		(duplicate_pad_numbers_are_jumpers no)
		(fp_line
			(start -0.7874 0.4064)
			(end -0.7874 -0.4064)
			(stroke
				(width 0.1524)
				(type default)
			)
			(layer "F.SilkS")
		)
		(fp_line
			(start 0.7874 0.4064)
			(end -0.7874 0.4064)
			(stroke
				(width 0.1524)
				(type default)
			)
			(layer "F.SilkS")
		)
		(fp_line
			(start -0.7874 -0.4064)
			(end 0.7874 -0.4064)
			(stroke
				(width 0.1524)
				(type default)
			)
			(layer "F.SilkS")
		)
		(fp_line
			(start 0.7874 -0.4064)
			(end 0.7874 0.4064)
			(stroke
				(width 0.1524)
				(type default)
			)
			(layer "F.SilkS")
		)
		(fp_line
			(start -0.67945 0.3048)
			(end -0.67945 -0.305054)
			(stroke
				(width 0.1)
				(type default)
			)
			(layer "F.Fab")
		)
		(fp_line
			(start -0.12065 0.3048)
			(end -0.67945 0.3048)
			(stroke
				(width 0.1)
				(type default)
			)
			(layer "F.Fab")
		)
		(fp_line
			(start 0.120396 0.3048)
			(end 0.120396 0.2794)
			(stroke
				(width 0.1)
				(type default)
			)
			(layer "F.Fab")
		)
		(fp_line
			(start 0.67945 0.3048)
			(end 0.120396 0.3048)
			(stroke
				(width 0.1)
				(type default)
			)
			(layer "F.Fab")
		)
		(fp_line
			(start -0.12065 0.2794)
			(end -0.12065 0.3048)
			(stroke
				(width 0.1)
				(type default)
			)
			(layer "F.Fab")
		)
		(fp_line
			(start 0.120396 0.2794)
			(end -0.12065 0.2794)
			(stroke
				(width 0.1)
				(type default)
			)
			(layer "F.Fab")
		)
		(fp_line
			(start -0.12065 -0.2794)
			(end 0.12065 -0.2794)
			(stroke
				(width 0.1)
				(type default)
			)
			(layer "F.Fab")
		)
		(fp_line
			(start 0.12065 -0.2794)
			(end 0.12065 -0.3048)
			(stroke
				(width 0.1)
				(type default)
			)
			(layer "F.Fab")
		)
		(fp_line
			(start 0.12065 -0.3048)
			(end 0.67945 -0.3048)
			(stroke
				(width 0.1)
				(type default)
			)
			(layer "F.Fab")
		)
		(fp_line
			(start 0.67945 -0.3048)
			(end 0.67945 0.3048)
			(stroke
				(width 0.1)
				(type default)
			)
			(layer "F.Fab")
		)
		(fp_line
			(start -0.67945 -0.305054)
			(end -0.12065 -0.305054)
			(stroke
				(width 0.1)
				(type default)
			)
			(layer "F.Fab")
		)
		(fp_line
			(start -0.12065 -0.305054)
			(end -0.12065 -0.2794)
			(stroke
				(width 0.1)
				(type default)
			)
			(layer "F.Fab")
		)
		(pad "1" smd circle
			(at -0.40005 0 270)
			(size 0 0)
			(layers "F.Cu" "F.Mask" "F.Paste")
			(net "CPU0_XTRIG_R2_L7")
		)
		(pad "2" smd circle
			(at 0.40005 0 270)
			(size 0 0)
			(layers "F.Cu" "F.Mask" "F.Paste")
			(net "CPU0_XTRIG_L7")
		)
	)
)
